(kicad_pcb
	(version 20241229)
	(generator "pcbnew")
	(generator_version "9.0")
	(general
		(thickness 1.711)
		(legacy_teardrops no)
	)
	(paper "A4")
	(title_block
		(title "Antmicro Baseboard for Jetson AGX Thor")
		(date "2026-02-18")
		(rev "1.1.0")
		(company "Antmicro Ltd")
		(comment 1 "www.antmicro.com")
		(comment 9 "footprints 488-491 of 1170")
	)
	(layers
		(0 "F.Cu" signal)
		(4 "In1.Cu" signal)
		(6 "In2.Cu" signal)
		(8 "In3.Cu" signal)
		(10 "In4.Cu" jumper)
		(12 "In5.Cu" signal)
		(14 "In6.Cu" signal)
		(16 "In7.Cu" signal)
		(18 "In8.Cu" signal)
		(2 "B.Cu" signal)
		(9 "F.Adhes" user "F.Adhesive")
		(11 "B.Adhes" user "B.Adhesive")
		(13 "F.Paste" user)
		(15 "B.Paste" user)
		(5 "F.SilkS" user "F.Silkscreen")
		(7 "B.SilkS" user "B.Silkscreen")
		(1 "F.Mask" user)
		(3 "B.Mask" user)
		(17 "Dwgs.User" user "User.Drawings")
		(19 "Cmts.User" user "User.Comments")
		(21 "Eco1.User" user "User.Eco1")
		(23 "Eco2.User" user "User.Eco2")
		(25 "Edge.Cuts" user)
		(27 "Margin" user)
		(31 "F.CrtYd" user "F.Courtyard")
		(29 "B.CrtYd" user "B.Courtyard")
		(35 "F.Fab" user)
		(33 "B.Fab" user)
	)
	(footprint "antmicro-footprints:R_0402_1005Metric"
		(layer "F.Cu")
		(at 87.95 64.5 180)
		(descr "Resistor SMD 0402")
		(tags "resistor SMD 0402")
		(property "Reference" "R300"
			(at 16.3 -8.65 0)
			(layer "F.SilkS")
			(effects
				(font
					(size 0.7 0.7)
					(thickness 0.15)
				)
				(justify right top)
			)
		)
		(property "Value" "R_10k_0402"
			(at -1.011843 1.772046 0)
			(layer "F.Fab")
			(effects
				(font
					(size 0.7 0.7)
					(thickness 0.15)
				)
				(justify right top)
			)
		)
		(property "Datasheet" "https://www.bourns.com/docs/product-datasheets/cr.pdf"
			(at 0 0 0)
			(layer "F.Fab")
			(hide yes)
			(effects
				(font
					(size 1.27 1.27)
					(thickness 0.15)
				)
			)
		)
		(property "Description" "SMD Chip Resistor, 10 kohm, ± 1%, 62.5 mW, 0402 [1005 Metric], Thick Film, General Purpose"
			(at 0 0 0)
			(layer "F.Fab")
			(hide yes)
			(effects
				(font
					(size 1.27 1.27)
					(thickness 0.15)
				)
			)
		)
		(property "MPN" "CR0402-FX-1002GLF"
			(at 0 0 180)
			(unlocked yes)
			(layer "F.Fab")
			(hide yes)
			(effects
				(font
					(size 1 1)
					(thickness 0.15)
				)
			)
		)
		(property "Manufacturer" "Bourns"
			(at 0 0 180)
			(unlocked yes)
			(layer "F.Fab")
			(hide yes)
			(effects
				(font
					(size 1 1)
					(thickness 0.15)
				)
			)
		)
		(property "License" "Apache-2.0"
			(at 0 0 180)
			(unlocked yes)
			(layer "F.Fab")
			(hide yes)
			(effects
				(font
					(size 1 1)
					(thickness 0.15)
				)
			)
		)
		(property "Author" "Antmicro"
			(at 0 0 180)
			(unlocked yes)
			(layer "F.Fab")
			(hide yes)
			(effects
				(font
					(size 1 1)
					(thickness 0.15)
				)
			)
		)
		(property "Val" "10k"
			(at 0 0 180)
			(unlocked yes)
			(layer "F.Fab")
			(hide yes)
			(effects
				(font
					(size 1 1)
					(thickness 0.15)
				)
			)
		)
		(property "Tolerance" "1%"
			(at 0 0 180)
			(unlocked yes)
			(layer "F.Fab")
			(hide yes)
			(effects
				(font
					(size 1 1)
					(thickness 0.15)
				)
			)
		)
		(sheetname "/SoM_Power/")
		(sheetfile "som_power.kicad_sch")
		(attr smd)
		(fp_poly
			(pts
				(xy -0.925 -0.47) (xy -0.925 0.47) (xy 0.925 0.47) (xy 0.925 -0.47)
			)
			(stroke
				(width 0.05)
				(type default)
			)
			(fill no)
			(layer "F.CrtYd")
		)
		(fp_poly
			(pts
				(xy -0.5 -0.25) (xy -0.5 0.25) (xy 0.5 0.25) (xy 0.5 -0.25)
			)
			(stroke
				(width 0.15)
				(type solid)
			)
			(fill no)
			(layer "F.Fab")
		)
		(fp_text user "License: Apache-2.0"
			(at -0.949999 5.169 0)
			(layer "F.Fab")
			(effects
				(font
					(size 0.7 0.7)
					(thickness 0.15)
				)
				(justify right top)
			)
		)
		(fp_text user "${REFERENCE}"
			(at -0.95 3.168 0)
			(layer "F.Fab")
			(effects
				(font
					(size 0.7 0.7)
					(thickness 0.15)
				)
				(justify right top)
			)
		)
		(fp_text user "Author: Antmicro"
			(at -0.95 4.169 0)
			(layer "F.Fab")
			(effects
				(font
					(size 0.7 0.7)
					(thickness 0.15)
				)
				(justify right top)
			)
		)
		(pad "1" smd roundrect
			(at -0.48 0 180)
			(size 0.59 0.64)
			(layers "F.Cu" "F.Mask" "F.Paste")
			(roundrect_rratio 0.25)
			(net 1032 "/SoM_Power/~{FORCE_SHDN}")
			(pintype "passive")
		)
		(pad "2" smd roundrect
			(at 0.48 0 180)
			(size 0.59 0.64)
			(layers "F.Cu" "F.Mask" "F.Paste")
			(roundrect_rratio 0.25)
			(net 1382 "Net-(R300-Pad2)")
			(pintype "passive")
		)
	)
	(footprint "antmicro-footprints:C_0402_1005Metric"
		(layer "F.Cu")
		(at 89.12 91.4)
		(descr "Capacitor SMD 0402")
		(tags "capacitor SMD 0402")
		(property "Reference" "C334"
			(at -3.82 0.45 0)
			(layer "F.SilkS")
			(effects
				(font
					(size 0.7 0.7)
					(thickness 0.15)
				)
				(justify left bottom)
			)
		)
		(property "Value" "C_100n_0402"
			(at -1.022927 2.155213 0)
			(layer "F.Fab")
			(effects
				(font
					(size 0.7 0.7)
					(thickness 0.15)
				)
				(justify left bottom)
			)
		)
		(property "Datasheet" "https://www.murata.com/products/productdetail?partno=GRM155R61H104KE14%23"
			(at 0 0 0)
			(layer "F.Fab")
			(hide yes)
			(effects
				(font
					(size 1.27 1.27)
					(thickness 0.15)
				)
			)
		)
		(property "Description" "SMD Multilayer Ceramic Capacitor, 0.1 µF, 50 V, 0402 [1005 Metric], ± 10%, X5R, GRM Series"
			(at 0 0 0)
			(layer "F.Fab")
			(hide yes)
			(effects
				(font
					(size 1.27 1.27)
					(thickness 0.15)
				)
			)
		)
		(property "Manufacturer" "Murata"
			(at 0 0 0)
			(unlocked yes)
			(layer "F.Fab")
			(hide yes)
			(effects
				(font
					(size 1 1)
					(thickness 0.15)
				)
			)
		)
		(property "MPN" "GRM155R61H104KE14D"
			(at 0 0 0)
			(unlocked yes)
			(layer "F.Fab")
			(hide yes)
			(effects
				(font
					(size 1 1)
					(thickness 0.15)
				)
			)
		)
		(property "Val" "100n"
			(at 0 0 0)
			(unlocked yes)
			(layer "F.Fab")
			(hide yes)
			(effects
				(font
					(size 1 1)
					(thickness 0.15)
				)
			)
		)
		(property "License" "Apache-2.0"
			(at 0 0 0)
			(unlocked yes)
			(layer "F.Fab")
			(hide yes)
			(effects
				(font
					(size 1 1)
					(thickness 0.15)
				)
			)
		)
		(property "Author" "Antmicro"
			(at 0 0 0)
			(unlocked yes)
			(layer "F.Fab")
			(hide yes)
			(effects
				(font
					(size 1 1)
					(thickness 0.15)
				)
			)
		)
		(property "Voltage" "50V"
			(at 0 0 0)
			(unlocked yes)
			(layer "F.Fab")
			(hide yes)
			(effects
				(font
					(size 1 1)
					(thickness 0.15)
				)
			)
		)
		(property "Dielectric" "X5R"
			(at 0 0 0)
			(unlocked yes)
			(layer "F.Fab")
			(hide yes)
			(effects
				(font
					(size 1 1)
					(thickness 0.15)
				)
			)
		)
		(sheetname "/SoM_IO2/")
		(sheetfile "som_io2.kicad_sch")
		(attr smd)
		(fp_rect
			(start -0.925 -0.47)
			(end 0.925 0.47)
			(stroke
				(width 0.05)
				(type default)
			)
			(fill no)
			(layer "F.CrtYd")
		)
		(fp_line
			(start -0.494 -0.25)
			(end 0.504 -0.25)
			(stroke
				(width 0.15)
				(type solid)
			)
			(layer "F.Fab")
		)
		(fp_line
			(start -0.494 0.248)
			(end -0.494 -0.25)
			(stroke
				(width 0.15)
				(type solid)
			)
			(layer "F.Fab")
		)
		(fp_line
			(start 0.504 -0.25)
			(end 0.504 0.248)
			(stroke
				(width 0.15)
				(type solid)
			)
			(layer "F.Fab")
		)
		(fp_line
			(start 0.504 0.248)
			(end -0.494 0.248)
			(stroke
				(width 0.15)
				(type solid)
			)
			(layer "F.Fab")
		)
		(fp_text user "${REFERENCE}"
			(at -0.939 4.599 0)
			(layer "F.Fab")
			(effects
				(font
					(size 0.7 0.7)
					(thickness 0.15)
				)
				(justify left bottom)
			)
		)
		(fp_text user "Author: Antmicro"
			(at -0.939 3.399 0)
			(layer "F.Fab")
			(effects
				(font
					(size 0.7 0.7)
					(thickness 0.15)
				)
				(justify left bottom)
			)
		)
		(fp_text user "License: Apache-2.0"
			(at -0.939 5.799 0)
			(layer "F.Fab")
			(effects
				(font
					(size 0.7 0.7)
					(thickness 0.15)
				)
				(justify left bottom)
			)
		)
		(pad "1" smd roundrect
			(at -0.48 0)
			(size 0.59 0.64)
			(layers "F.Cu" "F.Mask" "F.Paste")
			(roundrect_rratio 0.25)
			(net 591 "/Expansion connector/DP2.TX0+")
			(pintype "passive")
		)
		(pad "2" smd roundrect
			(at 0.48 0)
			(size 0.59 0.64)
			(layers "F.Cu" "F.Mask" "F.Paste")
			(roundrect_rratio 0.25)
			(net 1254 "/SoM_IO2/DP2.TX0_C+")
			(pintype "passive")
		)
	)
	(footprint "antmicro-footprints:R_0402_1005Metric"
		(layer "F.Cu")
		(at 179.4 106.95 180)
		(descr "Resistor SMD 0402")
		(tags "resistor SMD 0402")
		(property "Reference" "R36"
			(at -0.9 1.45 0)
			(layer "F.SilkS")
			(effects
				(font
					(size 0.7 0.7)
					(thickness 0.15)
				)
				(justify right top)
			)
		)
		(property "Value" "R_499k_0402"
			(at -1.011843 1.772047 0)
			(layer "F.Fab")
			(effects
				(font
					(size 0.7 0.7)
					(thickness 0.15)
				)
				(justify right top)
			)
		)
		(property "Datasheet" "https://www.mouser.com/datasheet/2/54/cr-1858361.pdf"
			(at 0 0 0)
			(layer "F.Fab")
			(hide yes)
			(effects
				(font
					(size 1.27 1.27)
					(thickness 0.15)
				)
			)
		)
		(property "Description" "SMD Chip Resistor, 499 kohm, ± 1%, 63 mW, 0402 [1005 Metric], Thick Film, General Purpose"
			(at 0 0 0)
			(layer "F.Fab")
			(hide yes)
			(effects
				(font
					(size 1.27 1.27)
					(thickness 0.15)
				)
			)
		)
		(property "MPN" "CR0402-FX-4993GLF"
			(at 0 0 180)
			(unlocked yes)
			(layer "F.Fab")
			(hide yes)
			(effects
				(font
					(size 1 1)
					(thickness 0.15)
				)
			)
		)
		(property "Manufacturer" "Bourns"
			(at 0 0 180)
			(unlocked yes)
			(layer "F.Fab")
			(hide yes)
			(effects
				(font
					(size 1 1)
					(thickness 0.15)
				)
			)
		)
		(property "License" "Apache-2.0"
			(at 0 0 180)
			(unlocked yes)
			(layer "F.Fab")
			(hide yes)
			(effects
				(font
					(size 1 1)
					(thickness 0.15)
				)
			)
		)
		(property "Author" "Antmicro"
			(at 0 0 180)
			(unlocked yes)
			(layer "F.Fab")
			(hide yes)
			(effects
				(font
					(size 1 1)
					(thickness 0.15)
				)
			)
		)
		(property "Val" "499k"
			(at 0 0 180)
			(unlocked yes)
			(layer "F.Fab")
			(hide yes)
			(effects
				(font
					(size 1 1)
					(thickness 0.15)
				)
			)
		)
		(property "Tolerance" "1%"
			(at 0 0 180)
			(unlocked yes)
			(layer "F.Fab")
			(hide yes)
			(effects
				(font
					(size 1 1)
					(thickness 0.15)
				)
			)
		)
		(sheetname "/DCDC/")
		(sheetfile "dcdc.kicad_sch")
		(attr smd exclude_from_pos_files exclude_from_bom dnp)
		(fp_rect
			(start -0.925 -0.47)
			(end 0.925 0.47)
			(stroke
				(width 0.05)
				(type default)
			)
			(fill no)
			(layer "F.CrtYd")
		)
		(fp_rect
			(start -0.5 -0.25)
			(end 0.5 0.25)
			(stroke
				(width 0.15)
				(type solid)
			)
			(fill no)
			(layer "F.Fab")
		)
		(fp_text user "Author: Antmicro"
			(at -0.95 4.169 0)
			(layer "F.Fab")
			(effects
				(font
					(size 0.7 0.7)
					(thickness 0.15)
				)
				(justify right top)
			)
		)
		(fp_text user "${REFERENCE}"
			(at -0.95 3.168 0)
			(layer "F.Fab")
			(effects
				(font
					(size 0.7 0.7)
					(thickness 0.15)
				)
				(justify right top)
			)
		)
		(fp_text user "License: Apache-2.0"
			(at -0.95 5.169 0)
			(layer "F.Fab")
			(effects
				(font
					(size 0.7 0.7)
					(thickness 0.15)
				)
				(justify right top)
			)
		)
		(pad "1" smd roundrect
			(at -0.48 0 180)
			(size 0.59 0.64)
			(layers "F.Cu" "F.Mask" "F.Paste")
			(roundrect_rratio 0.25)
			(net 1212 "/DCDC/5V_MODE1")
			(pintype "passive")
		)
		(pad "2" smd roundrect
			(at 0.48 0 180)
			(size 0.59 0.64)
			(layers "F.Cu" "F.Mask" "F.Paste")
			(roundrect_rratio 0.25)
			(net 18 "/DCDC/5V_VDD")
			(pintype "passive")
		)
	)
	(footprint "antmicro-footprints:SOD-523"
		(layer "F.Cu")
		(at 198.3 95.1)
		(property "Reference" "D16"
			(at -3.111 0.33 0)
			(layer "F.SilkS")
			(effects
				(font
					(size 0.7 0.7)
					(thickness 0.15)
				)
				(justify left bottom)
			)
		)
		(property "Value" "RB521S30T1G"
			(at 0 1.499 0)
			(layer "F.Fab")
			(effects
				(font
					(size 0.7 0.7)
					(thickness 0.15)
				)
				(justify left bottom)
			)
		)
		(property "Datasheet" "https://www.onsemi.com/pdf/datasheet/rb521s30t1-d.pdf"
			(at 0 0 0)
			(layer "F.Fab")
			(hide yes)
			(effects
				(font
					(size 1.27 1.27)
					(thickness 0.15)
				)
			)
		)
		(property "Description" "Small Signal Schottky Diode, Single, 30 V, 200 mA, 500 mV, 1 A, 125 °C"
			(at 0 0 0)
			(layer "F.Fab")
			(hide yes)
			(effects
				(font
					(size 1.27 1.27)
					(thickness 0.15)
				)
			)
		)
		(property "MPN" "RB521S30T1G"
			(at 0 0 0)
			(unlocked yes)
			(layer "F.Fab")
			(hide yes)
			(effects
				(font
					(size 1 1)
					(thickness 0.15)
				)
			)
		)
		(property "Manufacturer" "ON Semiconductor"
			(at 0 0 0)
			(unlocked yes)
			(layer "F.Fab")
			(hide yes)
			(effects
				(font
					(size 1 1)
					(thickness 0.15)
				)
			)
		)
		(property "Author" "Antmicro"
			(at 0 0 0)
			(unlocked yes)
			(layer "F.Fab")
			(hide yes)
			(effects
				(font
					(size 1 1)
					(thickness 0.15)
				)
			)
		)
		(property "License" "Apache-2.0"
			(at 0 0 0)
			(unlocked yes)
			(layer "F.Fab")
			(hide yes)
			(effects
				(font
					(size 1 1)
					(thickness 0.15)
				)
			)
		)
		(sheetname "/USB Debug, PD/")
		(sheetfile "usb_debug_pd.kicad_sch")
		(attr smd)
		(fp_line
			(start -0.35 -0.5)
			(end -0.35 0.5)
			(stroke
				(width 0.15)
				(type solid)
			)
			(layer "F.SilkS")
		)
		(fp_poly
			(pts
				(xy -1 -0.6) (xy 1 -0.6) (xy 1 0.6) (xy -1 0.6)
			)
			(stroke
				(width 0.05)
				(type solid)
			)
			(fill no)
			(layer "F.CrtYd")
		)
		(fp_line
			(start -0.652 -0.425)
			(end 0.65 -0.425)
			(stroke
				(width 0.15)
				(type solid)
			)
			(layer "F.Fab")
		)
		(fp_line
			(start -0.652 0.423)
			(end -0.652 -0.425)
			(stroke
				(width 0.15)
				(type solid)
			)
			(layer "F.Fab")
		)
		(fp_line
			(start -0.652 0.423)
			(end 0.65 0.423)
			(stroke
				(width 0.15)
				(type solid)
			)
			(layer "F.Fab")
		)
		(fp_line
			(start -0.35 -0.4)
			(end -0.35 0.4)
			(stroke
				(width 0.15)
				(type solid)
			)
			(layer "F.Fab")
		)
		(fp_line
			(start 0.65 -0.425)
			(end 0.65 0.423)
			(stroke
				(width 0.15)
				(type solid)
			)
			(layer "F.Fab")
		)
		(fp_text user "Author: Antmicro"
			(at -1.276 4.7 0)
			(layer "F.Fab")
			(effects
				(font
					(size 0.7 0.7)
					(thickness 0.15)
				)
				(justify left bottom)
			)
		)
		(fp_text user "License: Apache-2.0"
			(at -1.276 5.9 0)
			(layer "F.Fab")
			(effects
				(font
					(size 0.7 0.7)
					(thickness 0.15)
				)
				(justify left bottom)
			)
		)
		(fp_text user "${REFERENCE}"
			(at -1.276 3.499 0)
			(layer "F.Fab")
			(effects
				(font
					(size 0.7 0.7)
					(thickness 0.15)
				)
				(justify left bottom)
			)
		)
		(pad "1" smd roundrect
			(at -0.701 0)
			(size 0.5 0.6)
			(layers "F.Cu" "F.Mask" "F.Paste")
			(roundrect_rratio 0.25)
			(net 532 "/USB Debug, PD/SCK")
			(pinfunction "C")
			(pintype "passive")
		)
		(pad "2" smd roundrect
			(at 0.699001 0)
			(size 0.5 0.6)
			(layers "F.Cu" "F.Mask" "F.Paste")
			(roundrect_rratio 0.25)
			(net 531 "Net-(D16-A)")
			(pinfunction "A")
			(pintype "passive")
		)
	)
)
